(kicad_pcb
	(version 20260206)
	(generator "pcbnew")
	(generator_version "10.0")
	(general
		(thickness 1.6)
		(legacy_teardrops no)
	)
	(paper "A4")
	(title_block
		(title "Bryce Canyon_F.DPB_16315-1-OCP.brd")
		(comment 1 "Bryce Canyon / footprints 268-274 of 2223")
	)
	(layers
		(0 "F.Cu" signal "TOP")
		(4 "In1.Cu" signal "L2GND")
		(6 "In2.Cu" signal "L3")
		(8 "In3.Cu" signal "L4GND")
		(10 "In4.Cu" signal "L5")
		(12 "In5.Cu" signal "L6VCC")
		(14 "In6.Cu" signal "L7VCC")
		(16 "In7.Cu" signal "L8")
		(18 "In8.Cu" signal "L9GND")
		(20 "In9.Cu" signal "L10")
		(22 "In10.Cu" signal "L11GND")
		(2 "B.Cu" signal "BOTTOM")
		(9 "F.Adhes" user "F.Adhesive")
		(11 "B.Adhes" user "B.Adhesive")
		(13 "F.Paste" user "Package Geometry/Pastemask Top")
		(15 "B.Paste" user "Package Geometry/Pastemask Bottom")
		(5 "F.SilkS" user "Ref Des/Silkscreen Top")
		(7 "B.SilkS" user "Ref Des/Silkscreen Bottom")
		(1 "F.Mask" user "Board Geometry/Soldermask Top")
		(3 "B.Mask" user "Board Geometry/Soldermask Bottom")
		(17 "Dwgs.User" user "User.Drawings")
		(19 "Cmts.User" user "User.Comments")
		(21 "Eco1.User" user "User.Eco1")
		(23 "Eco2.User" user "User.Eco2")
		(25 "Edge.Cuts" user "Board Geometry/Outline")
		(27 "Margin" user)
		(31 "F.CrtYd" user "Package Geometry/Place Bound Top")
		(29 "B.CrtYd" user "Package Geometry/Place Bound Bottom")
		(35 "F.Fab" user "Ref Des/Assembly Top")
		(33 "B.Fab" user "Ref Des/Assembly Bottom")
	)
	(footprint ""
		(layer "F.Cu")
		(at 376.412252 -128.21158 180)
		(property "Reference" "R539"
			(at 0 0 180)
			(layer "F.SilkS")
			(hide yes)
			(effects
				(font
					(size 1.27 1.27)
				)
			)
		)
		(property "Value" "4K7R2J-2-GP"
			(at 0.064008 -3.993896 180)
			(unlocked yes)
			(layer "F.Fab")
			(hide yes)
			(effects
				(font
					(size 1.016 1.016)
					(thickness 0.1524)
				)
			)
		)
		(property "Device Type" "R402H16"
			(at 0.064008 -5.517896 180)
			(unlocked yes)
			(layer "F.Fab")
			(hide yes)
			(effects
				(font
					(size 1.016 1.016)
					(thickness 0.1524)
				)
			)
		)
		(duplicate_pad_numbers_are_jumpers no)
		(fp_line
			(start 0.508 -0.9398)
			(end -0.508 -0.9398)
			(stroke
				(width 0.1524)
				(type default)
			)
			(layer "F.SilkS")
		)
		(fp_line
			(start -0.508 -0.9398)
			(end -0.508 0.9398)
			(stroke
				(width 0.1524)
				(type default)
			)
			(layer "F.SilkS")
		)
		(fp_rect
			(start -0.508 0.9398)
			(end 0.508 -0.9398)
			(stroke
				(width 0)
				(type default)
			)
			(fill no)
			(layer "F.CrtYd")
		)
		(fp_rect
			(start -0.508 0.9398)
			(end 0.508 -0.9398)
			(stroke
				(width 0)
				(type default)
			)
			(fill no)
			(layer "F.Fab")
		)
		(pad "1" smd custom
			(at 0 -0.4445 180)
			(size 0.1397 0.1397)
			(layers "F.Cu" "F.Mask" "F.Paste")
			(net "DRIVE_A_20_FLT_LED")
			(options
				(clearance outline)
				(anchor circle)
			)
			(primitives
				(gr_poly
					(pts
						(arc
							(start -0.1778 -0.2794)
							(mid -0.249642 -0.249642)
							(end -0.2794 -0.1778)
						)
						(arc
							(start -0.2794 0.1778)
							(mid -0.249642 0.249642)
							(end -0.1778 0.2794)
						)
						(arc
							(start 0.1778 0.2794)
							(mid 0.249642 0.249642)
							(end 0.2794 0.1778)
						)
						(arc
							(start 0.2794 -0.1778)
							(mid 0.249642 -0.249642)
							(end 0.1778 -0.2794)
						)
					)
					(width 0)
					(fill yes)
				)
			)
		)
		(pad "2" smd custom
			(at 0 0.4445 180)
			(size 0.1397 0.1397)
			(layers "F.Cu" "F.Mask" "F.Paste")
			(net "GND")
			(options
				(clearance outline)
				(anchor circle)
			)
			(primitives
				(gr_poly
					(pts
						(arc
							(start -0.1778 -0.2794)
							(mid -0.249642 -0.249642)
							(end -0.2794 -0.1778)
						)
						(arc
							(start -0.2794 0.1778)
							(mid -0.249642 0.249642)
							(end -0.1778 0.2794)
						)
						(arc
							(start 0.1778 0.2794)
							(mid 0.249642 0.249642)
							(end 0.2794 0.1778)
						)
						(arc
							(start 0.2794 -0.1778)
							(mid 0.249642 -0.249642)
							(end 0.1778 -0.2794)
						)
					)
					(width 0)
					(fill yes)
				)
			)
		)
	)
	(footprint ""
		(layer "F.Cu")
		(at 161.878264 -304.310796 180)
		(property "Reference" "R255"
			(at 0 0 180)
			(layer "F.SilkS")
			(hide yes)
			(effects
				(font
					(size 1.27 1.27)
				)
			)
		)
		(property "Value" "130R3F-GP"
			(at -0.0254 -2.5146 180)
			(unlocked yes)
			(layer "F.Fab")
			(hide yes)
			(effects
				(font
					(size 1.016 1.016)
					(thickness 0.1524)
				)
			)
		)
		(property "Device Type" "R603H22"
			(at -0.0254 -4.0386 180)
			(unlocked yes)
			(layer "F.Fab")
			(hide yes)
			(effects
				(font
					(size 1.016 1.016)
					(thickness 0.1524)
				)
			)
		)
		(duplicate_pad_numbers_are_jumpers no)
		(fp_line
			(start 0.2032 0)
			(end 0.4826 0)
			(stroke
				(width 0.2032)
				(type default)
			)
			(layer "F.SilkS")
		)
		(fp_line
			(start -0.4826 0)
			(end -0.2032 0)
			(stroke
				(width 0.2032)
				(type default)
			)
			(layer "F.SilkS")
		)
		(fp_rect
			(start -0.5842 1.3335)
			(end 0.5842 -1.3335)
			(stroke
				(width 0)
				(type default)
			)
			(fill no)
			(layer "F.CrtYd")
		)
		(fp_rect
			(start -0.5842 1.3335)
			(end 0.5842 -1.3335)
			(stroke
				(width 0)
				(type default)
			)
			(fill no)
			(layer "F.Fab")
		)
		(pad "1" smd custom
			(at 0 -0.762 180)
			(size 0.2159 0.2159)
			(layers "F.Cu" "F.Mask" "F.Paste")
			(net "P5V_B")
			(options
				(clearance outline)
				(anchor circle)
			)
			(primitives
				(gr_poly
					(pts
						(arc
							(start -0.3302 -0.4318)
							(mid -0.402042 -0.402042)
							(end -0.4318 -0.3302)
						)
						(arc
							(start -0.4318 0.3302)
							(mid -0.402042 0.402042)
							(end -0.3302 0.4318)
						)
						(arc
							(start 0.3302 0.4318)
							(mid 0.402042 0.402042)
							(end 0.4318 0.3302)
						)
						(arc
							(start 0.4318 -0.3302)
							(mid 0.402042 -0.402042)
							(end 0.3302 -0.4318)
						)
					)
					(width 0)
					(fill yes)
				)
			)
		)
		(pad "2" smd custom
			(at 0 0.762 180)
			(size 0.2159 0.2159)
			(layers "F.Cu" "F.Mask" "F.Paste")
			(net "FLT_HDD29")
			(options
				(clearance outline)
				(anchor circle)
			)
			(primitives
				(gr_poly
					(pts
						(arc
							(start -0.3302 -0.4318)
							(mid -0.402042 -0.402042)
							(end -0.4318 -0.3302)
						)
						(arc
							(start -0.4318 0.3302)
							(mid -0.402042 0.402042)
							(end -0.3302 0.4318)
						)
						(arc
							(start 0.3302 0.4318)
							(mid 0.402042 0.402042)
							(end 0.4318 0.3302)
						)
						(arc
							(start 0.4318 -0.3302)
							(mid 0.402042 -0.402042)
							(end 0.3302 -0.4318)
						)
					)
					(width 0)
					(fill yes)
				)
			)
		)
	)
	(footprint ""
		(layer "F.Cu")
		(at 137.190734 -138.342624 90)
		(property "Reference" "U32"
			(at 0 0 90)
			(layer "F.SilkS")
			(hide yes)
			(effects
				(font
					(size 1.27 1.27)
				)
			)
		)
		(property "Value" "SN74LVC1G08DCKR-GP"
			(at -2.3368 -8.6868 90)
			(unlocked yes)
			(layer "F.Fab")
			(hide yes)
			(effects
				(font
					(size 1.016 1.016)
					(thickness 0.1524)
				)
			)
		)
		(property "Device Type" "SC70-5H44"
			(at -2.3114 -10.414 90)
			(unlocked yes)
			(layer "F.Fab")
			(hide yes)
			(effects
				(font
					(size 1.016 1.016)
					(thickness 0.1524)
				)
			)
		)
		(duplicate_pad_numbers_are_jumpers no)
		(fp_line
			(start 1.3843 -1.8034)
			(end 1.3843 -1.1176)
			(stroke
				(width 0.3302)
				(type default)
			)
			(layer "F.SilkS")
		)
		(fp_line
			(start 0.6604 -1.8034)
			(end 1.3843 -1.8034)
			(stroke
				(width 0.3302)
				(type default)
			)
			(layer "F.SilkS")
		)
		(fp_line
			(start 1.27 -1.7018)
			(end 1.27 1.7018)
			(stroke
				(width 0.1524)
				(type default)
			)
			(layer "F.SilkS")
		)
		(fp_line
			(start -1.27 -1.7018)
			(end 1.27 -1.7018)
			(stroke
				(width 0.1524)
				(type default)
			)
			(layer "F.SilkS")
		)
		(fp_line
			(start 1.27 1.7018)
			(end -1.27 1.7018)
			(stroke
				(width 0.1524)
				(type default)
			)
			(layer "F.SilkS")
		)
		(fp_line
			(start -1.27 1.7018)
			(end -1.27 -1.7018)
			(stroke
				(width 0.1524)
				(type default)
			)
			(layer "F.SilkS")
		)
		(fp_rect
			(start -1.524 1.9558)
			(end 1.524 -1.9558)
			(stroke
				(width 0)
				(type default)
			)
			(fill no)
			(layer "F.CrtYd")
		)
		(fp_poly
			(pts
				(xy -1.524 -1.9558) (xy 1.524 -1.9558) (xy 1.524 1.9558) (xy -1.524 1.9558)
			)
			(stroke
				(width 0)
				(type default)
			)
			(fill no)
			(layer "F.Fab")
		)
		(pad "1" smd rect
			(at 0.65024 -0.8255 90)
			(size 0.4064 1.2192)
			(layers "F.Cu" "F.Mask" "F.Paste")
			(net "P12V_A_PGOOD")
		)
		(pad "2" smd rect
			(at 0 -0.8255 90)
			(size 0.4064 1.2192)
			(layers "F.Cu" "F.Mask" "F.Paste")
			(net "COMP_A_PWR_EN")
		)
		(pad "3" smd rect
			(at -0.65024 -0.8255 90)
			(size 0.4064 1.2192)
			(layers "F.Cu" "F.Mask" "F.Paste")
			(net "GND")
		)
		(pad "4" smd rect
			(at -0.65024 0.8255 90)
			(size 0.4064 1.2192)
			(layers "F.Cu" "F.Mask" "F.Paste")
			(net "MB0_HS_ENABLE")
		)
		(pad "5" smd rect
			(at 0.65024 0.8255 90)
			(size 0.4064 1.2192)
			(layers "F.Cu" "F.Mask" "F.Paste")
			(net "P3V3_A_BIAS")
		)
	)
	(footprint ""
		(layer "F.Cu")
		(at 238.506 -256.5908)
		(property "Reference" "C13"
			(at 0 0 0)
			(layer "F.SilkS")
			(hide yes)
			(effects
				(font
					(size 1.27 1.27)
				)
			)
		)
		(property "Value" "SC1U16V3KX-5GP"
			(at 0 -2.8194 0)
			(unlocked yes)
			(layer "F.Fab")
			(hide yes)
			(effects
				(font
					(size 1.016 1.016)
					(thickness 0.1524)
				)
			)
		)
		(property "Device Type" "C603H36"
			(at 0 -4.3434 0)
			(unlocked yes)
			(layer "F.Fab")
			(hide yes)
			(effects
				(font
					(size 1.016 1.016)
					(thickness 0.1524)
				)
			)
		)
		(duplicate_pad_numbers_are_jumpers no)
		(fp_line
			(start 0.508 0)
			(end -0.508 0)
			(stroke
				(width 0.2032)
				(type default)
			)
			(layer "F.SilkS")
		)
		(fp_rect
			(start -0.5842 1.3335)
			(end 0.5842 -1.3335)
			(stroke
				(width 0)
				(type default)
			)
			(fill no)
			(layer "F.CrtYd")
		)
		(fp_rect
			(start -0.5842 1.3335)
			(end 0.5842 -1.3335)
			(stroke
				(width 0)
				(type default)
			)
			(fill no)
			(layer "F.Fab")
		)
		(pad "1" smd custom
			(at 0 -0.762)
			(size 0.2159 0.2159)
			(layers "F.Cu" "F.Mask" "F.Paste")
			(net "P3V3_STBY_A")
			(options
				(clearance outline)
				(anchor circle)
			)
			(primitives
				(gr_poly
					(pts
						(arc
							(start -0.3302 -0.4318)
							(mid -0.402042 -0.402042)
							(end -0.4318 -0.3302)
						)
						(arc
							(start -0.4318 0.3302)
							(mid -0.402042 0.402042)
							(end -0.3302 0.4318)
						)
						(arc
							(start 0.3302 0.4318)
							(mid 0.402042 0.402042)
							(end 0.4318 0.3302)
						)
						(arc
							(start 0.4318 -0.3302)
							(mid 0.402042 -0.402042)
							(end 0.3302 -0.4318)
						)
					)
					(width 0)
					(fill yes)
				)
			)
		)
		(pad "2" smd custom
			(at 0 0.762)
			(size 0.2159 0.2159)
			(layers "F.Cu" "F.Mask" "F.Paste")
			(net "GND")
			(options
				(clearance outline)
				(anchor circle)
			)
			(primitives
				(gr_poly
					(pts
						(arc
							(start -0.3302 -0.4318)
							(mid -0.402042 -0.402042)
							(end -0.4318 -0.3302)
						)
						(arc
							(start -0.4318 0.3302)
							(mid -0.402042 0.402042)
							(end -0.3302 0.4318)
						)
						(arc
							(start 0.3302 0.4318)
							(mid 0.402042 0.402042)
							(end 0.4318 0.3302)
						)
						(arc
							(start 0.4318 -0.3302)
							(mid 0.402042 -0.402042)
							(end 0.3302 -0.4318)
						)
					)
					(width 0)
					(fill yes)
				)
			)
		)
	)
	(footprint ""
		(layer "F.Cu")
		(at 272.8976 19.143472)
		(property "Reference" "R616"
			(at 0 0 0)
			(layer "F.SilkS")
			(hide yes)
			(effects
				(font
					(size 1.27 1.27)
				)
			)
		)
		(property "Value" "10KR2F-2-GP"
			(at 0.064008 -3.993896 0)
			(unlocked yes)
			(layer "F.Fab")
			(hide yes)
			(effects
				(font
					(size 1.016 1.016)
					(thickness 0.1524)
				)
			)
		)
		(property "Device Type" "R402H16"
			(at 0.064008 -5.517896 0)
			(unlocked yes)
			(layer "F.Fab")
			(hide yes)
			(effects
				(font
					(size 1.016 1.016)
					(thickness 0.1524)
				)
			)
		)
		(duplicate_pad_numbers_are_jumpers no)
		(fp_line
			(start -0.508 -0.9398)
			(end -0.508 0.9398)
			(stroke
				(width 0.1524)
				(type default)
			)
			(layer "F.SilkS")
		)
		(fp_line
			(start 0.508 -0.9398)
			(end -0.508 -0.9398)
			(stroke
				(width 0.1524)
				(type default)
			)
			(layer "F.SilkS")
		)
		(fp_rect
			(start -0.508 0.9398)
			(end 0.508 -0.9398)
			(stroke
				(width 0)
				(type default)
			)
			(fill no)
			(layer "F.CrtYd")
		)
		(fp_rect
			(start -0.508 0.9398)
			(end 0.508 -0.9398)
			(stroke
				(width 0)
				(type default)
			)
			(fill no)
			(layer "F.Fab")
		)
		(pad "1" smd custom
			(at 0 -0.4445)
			(size 0.1397 0.1397)
			(layers "F.Cu" "F.Mask" "F.Paste")
			(net "SCC_B_FAULT_LED")
			(options
				(clearance outline)
				(anchor circle)
			)
			(primitives
				(gr_poly
					(pts
						(arc
							(start -0.1778 -0.2794)
							(mid -0.249642 -0.249642)
							(end -0.2794 -0.1778)
						)
						(arc
							(start -0.2794 0.1778)
							(mid -0.249642 0.249642)
							(end -0.1778 0.2794)
						)
						(arc
							(start 0.1778 0.2794)
							(mid 0.249642 0.249642)
							(end 0.2794 0.1778)
						)
						(arc
							(start 0.2794 -0.1778)
							(mid 0.249642 -0.249642)
							(end 0.1778 -0.2794)
						)
					)
					(width 0)
					(fill yes)
				)
			)
		)
		(pad "2" smd custom
			(at 0 0.4445)
			(size 0.1397 0.1397)
			(layers "F.Cu" "F.Mask" "F.Paste")
			(net "GND")
			(options
				(clearance outline)
				(anchor circle)
			)
			(primitives
				(gr_poly
					(pts
						(arc
							(start -0.1778 -0.2794)
							(mid -0.249642 -0.249642)
							(end -0.2794 -0.1778)
						)
						(arc
							(start -0.2794 0.1778)
							(mid -0.249642 0.249642)
							(end -0.1778 0.2794)
						)
						(arc
							(start 0.1778 0.2794)
							(mid 0.249642 0.249642)
							(end 0.2794 0.1778)
						)
						(arc
							(start 0.2794 -0.1778)
							(mid 0.249642 -0.249642)
							(end 0.1778 -0.2794)
						)
					)
					(width 0)
					(fill yes)
				)
			)
		)
	)
	(footprint ""
		(layer "F.Cu")
		(at 469.904318 -49.29505 90)
		(property "Reference" "R951"
			(at 0 0 90)
			(layer "F.SilkS")
			(hide yes)
			(effects
				(font
					(size 1.27 1.27)
				)
			)
		)
		(property "Value" "200KR2F-L-GP"
			(at 0.064008 -3.993896 90)
			(unlocked yes)
			(layer "F.Fab")
			(hide yes)
			(effects
				(font
					(size 1.016 1.016)
					(thickness 0.1524)
				)
			)
		)
		(property "Device Type" "R402H16"
			(at 0.064008 -5.517896 90)
			(unlocked yes)
			(layer "F.Fab")
			(hide yes)
			(effects
				(font
					(size 1.016 1.016)
					(thickness 0.1524)
				)
			)
		)
		(duplicate_pad_numbers_are_jumpers no)
		(fp_line
			(start 0.508 -0.9398)
			(end -0.508 -0.9398)
			(stroke
				(width 0.1524)
				(type default)
			)
			(layer "F.SilkS")
		)
		(fp_line
			(start -0.508 -0.9398)
			(end -0.508 0.9398)
			(stroke
				(width 0.1524)
				(type default)
			)
			(layer "F.SilkS")
		)
		(fp_rect
			(start -0.508 0.9398)
			(end 0.508 -0.9398)
			(stroke
				(width 0)
				(type default)
			)
			(fill no)
			(layer "F.CrtYd")
		)
		(fp_rect
			(start -0.508 0.9398)
			(end 0.508 -0.9398)
			(stroke
				(width 0)
				(type default)
			)
			(fill no)
			(layer "F.Fab")
		)
		(pad "1" smd custom
			(at 0 -0.4445 90)
			(size 0.1397 0.1397)
			(layers "F.Cu" "F.Mask" "F.Paste")
			(net "SW_HDD_R35")
			(options
				(clearance outline)
				(anchor circle)
			)
			(primitives
				(gr_poly
					(pts
						(arc
							(start -0.1778 -0.2794)
							(mid -0.249642 -0.249642)
							(end -0.2794 -0.1778)
						)
						(arc
							(start -0.2794 0.1778)
							(mid -0.249642 0.249642)
							(end -0.1778 0.2794)
						)
						(arc
							(start 0.1778 0.2794)
							(mid 0.249642 0.249642)
							(end 0.2794 0.1778)
						)
						(arc
							(start 0.2794 -0.1778)
							(mid 0.249642 -0.249642)
							(end 0.1778 -0.2794)
						)
					)
					(width 0)
					(fill yes)
				)
			)
		)
		(pad "2" smd custom
			(at 0 0.4445 90)
			(size 0.1397 0.1397)
			(layers "F.Cu" "F.Mask" "F.Paste")
			(net "SW_HDD_N35")
			(options
				(clearance outline)
				(anchor circle)
			)
			(primitives
				(gr_poly
					(pts
						(arc
							(start -0.1778 -0.2794)
							(mid -0.249642 -0.249642)
							(end -0.2794 -0.1778)
						)
						(arc
							(start -0.2794 0.1778)
							(mid -0.249642 0.249642)
							(end -0.1778 0.2794)
						)
						(arc
							(start 0.1778 0.2794)
							(mid 0.249642 0.249642)
							(end 0.2794 0.1778)
						)
						(arc
							(start 0.2794 -0.1778)
							(mid 0.249642 -0.249642)
							(end 0.1778 -0.2794)
						)
					)
					(width 0)
					(fill yes)
				)
			)
		)
	)
	(footprint ""
		(layer "F.Cu")
		(at 83.393534 -31.394146 180)
		(property "Reference" "R30"
			(at 0 0 180)
			(layer "F.SilkS")
			(hide yes)
			(effects
				(font
					(size 1.27 1.27)
				)
			)
		)
		(property "Value" "0R2J-2-GP"
			(at 0.064008 -3.993896 180)
			(unlocked yes)
			(layer "F.Fab")
			(hide yes)
			(effects
				(font
					(size 1.016 1.016)
					(thickness 0.1524)
				)
			)
		)
		(property "Device Type" "R402H16"
			(at 0.064008 -5.517896 180)
			(unlocked yes)
			(layer "F.Fab")
			(hide yes)
			(effects
				(font
					(size 1.016 1.016)
					(thickness 0.1524)
				)
			)
		)
		(duplicate_pad_numbers_are_jumpers no)
		(fp_line
			(start 0.508 -0.9398)
			(end -0.508 -0.9398)
			(stroke
				(width 0.1524)
				(type default)
			)
			(layer "F.SilkS")
		)
		(fp_line
			(start -0.508 -0.9398)
			(end -0.508 0.9398)
			(stroke
				(width 0.1524)
				(type default)
			)
			(layer "F.SilkS")
		)
		(fp_rect
			(start -0.508 0.9398)
			(end 0.508 -0.9398)
			(stroke
				(width 0)
				(type default)
			)
			(fill no)
			(layer "F.CrtYd")
		)
		(fp_rect
			(start -0.508 0.9398)
			(end 0.508 -0.9398)
			(stroke
				(width 0)
				(type default)
			)
			(fill no)
			(layer "F.Fab")
		)
		(pad "1" smd custom
			(at 0 -0.4445 180)
			(size 0.1397 0.1397)
			(layers "F.Cu" "F.Mask" "F.Paste")
			(net "IO_EXP10_SCL")
			(options
				(clearance outline)
				(anchor circle)
			)
			(primitives
				(gr_poly
					(pts
						(arc
							(start -0.1778 -0.2794)
							(mid -0.249642 -0.249642)
							(end -0.2794 -0.1778)
						)
						(arc
							(start -0.2794 0.1778)
							(mid -0.249642 0.249642)
							(end -0.1778 0.2794)
						)
						(arc
							(start 0.1778 0.2794)
							(mid 0.249642 0.249642)
							(end 0.2794 0.1778)
						)
						(arc
							(start 0.2794 -0.1778)
							(mid 0.249642 -0.249642)
							(end 0.1778 -0.2794)
						)
					)
					(width 0)
					(fill yes)
				)
			)
		)
		(pad "2" smd custom
			(at 0 0.4445 180)
			(size 0.1397 0.1397)
			(layers "F.Cu" "F.Mask" "F.Paste")
			(net "I2C_BMC_A_MISC_SCL")
			(options
				(clearance outline)
				(anchor circle)
			)
			(primitives
				(gr_poly
					(pts
						(arc
							(start -0.1778 -0.2794)
							(mid -0.249642 -0.249642)
							(end -0.2794 -0.1778)
						)
						(arc
							(start -0.2794 0.1778)
							(mid -0.249642 0.249642)
							(end -0.1778 0.2794)
						)
						(arc
							(start 0.1778 0.2794)
							(mid 0.249642 0.249642)
							(end 0.2794 0.1778)
						)
						(arc
							(start 0.2794 -0.1778)
							(mid 0.249642 -0.249642)
							(end 0.1778 -0.2794)
						)
					)
					(width 0)
					(fill yes)
				)
			)
		)
	)
)
